# BARRELEYE_G2-FPDB_POST-EVT-HW-EBOM-X00_20161123-add_2nd_source_X08-20161215-Final-b.xls — PWA BOM (bom)
| FOXCONN TECHNOLOGY GROUP |  |  |  |  |  |  |  |  |  |  |  |  |  |  |  |  |  |  |  |
| BILL OF MATERIAL |  |  |  |  |  |  |  |  |  |  |  |  |  |  |  |  |  |  |  |
| REV OF  BOM | X08 | CUSTOMER |  | <name> |  | CUSTOMER P/N |  | PWA P/N： | PWA DESCRIPTION |  |  |  | PRODUCT CODE |  |  | PWA  REV |  | DATE |  |
| Sourcing (Single/Sole/Multi) | Critical Commodity (Y or N) | Component Class (1, 2, other) | Customer PSL (Y or N) | Line Item | Item Number | Foxconn P/N | Customer P/N | Part Description | Manufacturer  Full Name | Manufacturer  Part Number | Qty | RoHS Status | Location | CC Qual Build: | Qual by (Customer / ODM ?) | The Date of Change Part or Add 2nd Source | Configuration Identifier | Customer Comments | ODM Comments |
|  |  |  |  | 1 | 1 | 0101E1E00-000-G |  | PCB,Zaius-Fan Board EVT-X00,OSP,Red,6L,1.300*2.362,G | GCE | 0101E1E00-000-G | 1 | G | PCB |  |  |  |  |  |  |
|  |  |  |  |  | 1 | 0101E1E00-000-G |  | PCB,Zaius-Fan Board EVT-X00,OSP,Red,6L,1.300*2.362,G | FOUNDER | 0101E1E00-000-G |  | G |  |  |  |  |  |  |  |
|  |  |  |  | 2 | 2 | 620103700-015-G | - | CAP,100nF,+/-10%,X7R,10V,G,SMD0402 | MURATA | GRM155R71A104K | 20 | G | C1,C2,C3,PHAC5,C18,C19,C22,C24,C26,C28,C30,C32,C34,C35,C2111,C2112,C2113,C2114,C2115,C2116 |  |  |  |  |  |  |
|  |  |  |  |  | 2 | 620103700-012-G |  | CAP,0.1uF,+/-10%,X7R,10V,G,SMD0402 | WALSIN | 0402B104K100CT |  | G |  |  |  |  |  |  |  |
|  |  |  |  |  | 2 | 620103700-023-G |  | CAP,100nF,+/-10%,X7R,10V,G,SMD0402 | TAIYO | LMK105B7104KV-F |  | G |  |  |  |  |  |  |  |
|  |  |  |  |  | 2 | 620103700-026-G |  | CAP,100nF,+/-10%,X7R,10V,G,SMD0402 | SAMSUNG | CL05B104KP5NNNC |  | G |  |  |  |  |  |  |  |
|  |  |  |  | 3 | 3 | 62010BN00-015-G | - | CAP,1uF,+/-10%,X5R,6.3V,G,SMD0402 | MURATA | GRM155R60J105K | 2 | G | C4,C11 |  |  |  |  |  |  |
|  |  |  |  |  | 3 | 62010BN01-023-G |  | CAP,1uF,+/-10%,X5R,6.3V,G,SMD0402 | TAIYO | JMK105BJ105KV-F |  | G |  |  |  |  |  |  |  |
|  |  |  |  |  | 3 | 62010BN00-026-G |  | CAP,1uF,+/-10%,X5R,6.3V,G,SMD0402 | SAMSUNG | CL05A105KQ5NNNC |  | G |  |  |  |  |  |  |  |
|  |  |  |  | 4 | 4 | 620106200-015-G | - | CAP,10nF,+/-10%,X7R,16V,G,SMD0402 | MURATA | GRM155R71C103KA01D | 2 | G | C5,C12 |  |  |  |  |  |  |
|  |  |  |  |  | 4 | 620106200-012-G |  | CAP,10nF,+/-10%,X7R,16V,G,SMD0402 | WALSIN | 0402B103K160CT |  | G |  |  |  |  |  |  |  |
|  |  |  |  |  | 4 | 620106200-026-G |  | CAP,10nF,+/-10%,X7R,16V,G,SMD0402 | SAMSUNG | CL05B103KO5NNNC |  | G |  |  |  |  |  |  |  |
|  |  |  |  |  | 4 | 620106200-023-G |  | CAP,10nF,+/-10%,X7R,16V,G,SMD0402 | TAIYO | EMK105B7103KV-F |  | G |  |  |  |  |  |  |  |
|  |  |  |  | 5 | 5 | 620101T02-015-G | - | CAP,100nF,+/-10%,X7R,16V,G,SMD0402 | MURATA | GRM155R71C104K | 16 | G | C6,C7,C9,PSRC10,C13,C14,C16,C20,C21,C38,C39,C46,C71,C72,C362,C394 |  |  |  |  |  |  |
|  |  |  |  |  | 5 | 620101T00-012-G |  | CAP,100nF,+/-10%,X7R,16V,G,SMD0402 | WALSIN | 0402B104K160CT |  | G |  |  |  |  |  |  |  |
|  |  |  |  |  | 5 | 620101T00-026-G |  | CAP,100nF,+/-10%,X7R,16V,G,SMD0402 | SAMSUNG | CL05B104KO5NNNC |  | G |  |  |  |  |  |  |  |
|  |  |  |  |  | 5 | 620101T00-015-G |  | CAP,100nF,+/-10%,X7R,16V,G,SMD0402 | MURATA | GRM155R71C104KA88D |  | G |  |  |  |  |  |  |  |
|  |  |  |  | 6 | 6 | 620130V00-015-G |  | CAP,10uF,+/-20%,X6S,16V,G,SMD0603 | MURATA | GRM188C81C106MA73D | 16 | G | C8,C10,C15,C17,C23,C25,C27,C29,C31,C33,C40,C43,C47,C50,C53,C56 |  |  |  |  |  |  |
|  |  |  |  |  | 6 | 620130V00-023-G |  | CAP,10uF,+/-20%,X6S,16V,G,SMD0603 | TAIYO | EMK107BC6106MA-T |  | G |  |  |  |  |  |  |  |
|  |  |  |  | 7 | 7 | 620103K00-015-G | - | CAP,1nF,+/-10%,X7R,50V,G,SMD0402 | MURATA | GRM155R71H102K | 3 | G | PHAC2,C36,C37 |  |  |  |  |  |  |
|  |  |  |  |  | 7 | 620103K00-012-G |  | CAP,1nF,+/-10%,X7R,50V,G,SMD0402 | WALSIN | 0402B102K500CT |  | G |  |  |  |  |  |  |  |
|  |  |  |  |  | 7 | 620103K00-026-G |  | CAP,1nF,+/-10%,X7R,50V,G,SMD0402 | SAMSUNG | CL05B102KB5NNNC |  | G |  |  |  |  |  |  |  |
|  |  |  |  |  | 7 | 620103K00-023-G |  | CAP,1nF,+/-10%,X7R,50V,G,SMD0402 | TAIYO | UMK105B7102KV-F |  | G |  |  |  |  |  |  |  |
|  |  |  |  | 8 | 8 | 620100L00-015-G | - | CAP,22pF,+/-5%,NPO(C0G),50V,G,SMD0402 | MURATA | GRM1555C1H220J | 12 | G | C41,C42,C44,C45,C48,C49,C51,C52,C54,C55,C57,C58 |  |  |  |  |  |  |
|  |  |  |  |  | 8 | 620100L08-012-G |  | CAP,22pF,+/-5%,NPO(C0G),50V,G,SMD0402 | WALSIN | 0402N220J500CT |  | G |  |  |  |  |  |  |  |
|  |  |  |  |  | 8 | 620100L00-026-G |  | CAP,22pF,+/-5%,NPO(C0G),50V,G,SMD0402 | SAMSUNG | CL05C220JB5NNNC |  | G |  |  |  |  |  |  |  |
|  |  |  |  |  | 8 | 620100L00-023-G |  | CAP,22pF,+/-5%,NPO(C0G),50V,G,SMD0402 | TAIYO | UMK105CG220JV-F |  | G |  |  |  |  |  |  |  |
|  |  |  |  | 9 | 9 | 62012FR00-015-G |  | CAP,10uF,+/-20%,X5R,25V,G,SMD0603 | MURATA | GRM188R61E106M | 2 | G | C398,C399 |  |  |  |  |  |  |
|  |  |  |  |  | 9 | 62012FR00-023-G |  | CAP,10uF,+/-20%,X5R,25V,G,SMD0603 | TAIYO | TMK107BBJ106MA-T |  | G |  |  |  |  |  |  |  |
|  |  |  |  |  | 9 | 62012FR00-026-G |  | CAP,10uF,+/-20%,X5R,25V,G,SMD0603 | SAMSUNG | CL10A106MA8NRNC |  | G |  |  |  |  |  |  |  |
|  |  |  |  | 10 | 10 | 620100D00-015-G |  | CAP,100nF,+/-10%,X7R,16V,G,SMD0603 | MURATA | GRM188R71C104K | 1 | G | C400 |  |  |  |  |  |  |
|  |  |  |  |  | 10 | 620100D00-012-G |  | CAP,100nF,+/-10%,X7R,16V,G,SMD0603 | WALSIN | 0603B104K160CT |  | G |  |  |  |  |  |  |  |
|  |  |  |  |  | 10 | 620100D00-026-G |  | CAP,100nF,+/-10%,X7R,16V,G,SMD0603 | SAMSUNG | CL10B104KO8NNNC |  | G |  |  |  |  |  |  |  |
|  |  |  |  | 11 | 11 | 62012A400-015-G | - | CAP,100nF,+/-10%,X7R,25V,G,SMD0402 | MURATA | GRM155R71E104KE14D | 7 | G | PSRC1,PSUC3,PEUC3,PSRC6,PHAC19,PHAC20,C2117 |  |  |  |  |  |  |
|  |  |  |  |  | 11 | 62012A400-023-G |  | CAP,100nF,+/-10%,X7R,25V,G,SMD0402 | TAIYO | TMK105B7104KV-FR |  | G |  |  |  |  |  |  |  |
|  |  |  |  |  | 11 | 62012A400-026-G |  | CAP,100nF,+/-10%,X7R,25V,G,SMD0402 | SAMSUNG | CL05B104KA5NNNC |  | G |  |  |  |  |  |  |  |
|  |  |  |  |  | 11 | 62012A400-012-G |  | CAP,100nF,+/-10%,X7R,25V,G,SMD0402 | WALSIN | 0402B104K250CT |  | G |  |  |  |  |  |  |  |
|  |  |  |  | 12 | 12 | 610107C00-017-G |  | RES,10KOhm,+/-5%,1/16W,G,SMD0402 | KOA | RK73B1ETTP103J | 2 | G | R250,R259 |  |  |  |  |  |  |
|  |  |  |  |  | 12 | 610107C00-012-G |  | RES,10KOhm,+/-5%,1/16W,G,SMD0402 | WALSIN | WR04X103JTL |  | G |  |  |  |  |  |  |  |
|  |  |  |  |  | 12 | 610107C00-011-G |  | RES,10KOhm,+/-5%,1/16W,G,SMD0402 | YAGEO | RC0402JR-0710KL |  | G |  |  |  |  |  |  |  |
|  |  |  |  |  | 12 | 610107C00-044-G |  | RES,10KOhm,+/-5%,1/16W,G,SMD0402 | TA-I | RM04JTN103 |  | G |  |  |  |  |  |  |  |
|  |  |  |  |  | 12 | 610107C00-024-G |  | RES,10KOhm,+/-5%,1/16W,G,SMD0402 | PANASONIC | ERJ2GEJ103X |  | G |  |  |  |  |  |  |  |
|  |  |  |  |  | 12 | 610107C00-029-G |  | RES,10KOhm,+/-5%,1/16W,G,SMD0402 | VISHAY | CRCW040210K0JNED |  | G |  |  |  |  |  |  |  |
|  |  |  |  | 13 | 13 | 520100200-237-G | - | DIODE,Switching,1N4148W-7-F,100V,0.15A,G,SOD123-2,SMD | DIODES | 1N4148W-7-F | 13 | G | D1,D2,D3,D4,D5,PHAD6,D6,D7,D8,D9,D10,D11,D12 |  |  |  |  |  |  |
|  |  |  |  | 14 | 14 | 730101C00-086-G |  | Fuse,Slow blow,125V,30A,G,SMD | LITTELFUSE | 0456030.ER | 3 | G | FS1,FS2,FS10 |  |  |  |  |  |  |
|  |  |  |  | 15 | 15 | 730106S00-088-G |  | Fuse,Fast acting,125V,15A,G,SMD2010 | COOPER | CB61F15A-TR2 | 1 | G | FS3 |  |  |  |  |  |  |
|  |  |  |  | 16 | 16 | 730103M00-086-G |  | Fuse,Fast acting,32V,5A,G,SMD0603 | LITTELFUSE | 0438005.WR | 6 | G | FS4,FS5,FS6,FS7,FS8,FS9 |  |  |  |  |  |  |
|  |  |  |  | 17 | 17 | 340699J00-317-G |  | CONN,Header,WTB,1X8,V/T,Whi,2.54mm,G,DIP-8 | MOLEX | 22-23-2081 | 6 | G | J4,J5,J6,J7,J8,J9 |  |  |  |  |  |  |
|  |  |  |  | 18 | 18 | 52113DU00-289-G |  | LED,Hyper Red,LTS-2307CKD-P,G,5V,25mA,G,SMD-10 | LITE-ON | LTS-2307CKD-P | 2 | G | LED1,LED2 |  |  |  |  |  |  |
|  |  |  |  | 19 | 19 | 72010KB01-016-G | - | FB,330 Ohm@100MHz,+/-25%,2.5A,50mOhm,G,SMD0805 | TDK | MPZ2012S331AT | 6 | G | L1,L2,L3,L4,L5,L6 |  |  |  |  |  |  |
|  |  |  |  | 20 | 20 | 62111CS00-024-G |  | ECAP,68uF,+/-20%,100V,105C,G,SMD12.5*13.5,ESR<=320mOhm | PANASONIC | EEVFK2A680Q | 4 | G | PSUCE1,PEUCE1,PSUCE2,PEUCE2 |  |  |  |  |  |  |
|  |  |  |  | 21 | 21 | 62120HJ00-022-G | - | ECAP,SPEA,270uF,+/-20%,16V,105C,G,SMD6.3X9.9,ESR<=8mOhm | SANYO | 16SVPG270M | 2 | G | PSUCE4,PEUCE4 |  |  |  |  |  |  |
|  |  |  |  | 22 | 22 | 62011J601-015-G |  | CAP,2.2uF,+/-10%,X7R,100V,G,SMD1210 | MURATA | GRM32ER72A225K | 4 | G | PSUC1,PEUC1,PSUC2,PEUC2 |  |  |  |  |  |  |
|  |  |  |  |  | 22 | 62011J600-026-G |  | CAP,2.2uF,+/-10%,X7R,100V,G,SMD1210 | SAMSUNG | CL32B225KCJSNNE |  | G |  |  |  |  |  |  |  |
|  |  |  |  | 23 | 23 | 62011F100-015-G |  | CAP,1uF,+/-10%,X7R,25V,G,SMD0603 | MURATA | GRM188R71E105K | 2 | G | PSUC4,PEUC4 |  |  |  |  |  |  |
|  |  |  |  |  | 23 | 62011F100-023-G |  | CAP,1uF,+/-10%,X7R,25V,G,SMD0603 | TAIYO | TMK107B7105KA-T |  | G |  |  |  |  |  |  |  |
|  |  |  |  |  | 23 | 62011F100-026-G |  | CAP,1uF,+/-10%,X7R,25V,G,SMD0603 | SAMSUNG | CL10B105KA8NNNC |  | G |  |  |  |  |  |  |  |
|  |  |  |  | 24 | 24 | 62012T500-015-G |  | CAP,22uF,+/-20%,X7S,25V,G,SMD1206 | MURATA | GRM31CC71E226ME11L | 14 | G | PSRC2,PSUC5,PEUC5,PSUC6,PEUC6,PSUC7,PEUC7,PSUC8,PEUC8,PSUC9,PEUC9,PSUC10,PEUC10,PSRC17 |  |  |  |  |  |  |
|  |  |  |  | 25 | 25 | 51030CQ00-185-G |  | MOS N,2N7002,60V,115mA,7.5ohm@5V,G,SOT23-3,SMD | FAIRCHILD | 2N7002 | 2 | G | PSUQ1,PEUQ1 |  |  |  |  |  |  |
|  |  |  |  | 26 | 26 | 61010G500-017-G | - | RES,10KOhm,+/-1%,1/16W,G,SMD0402 | KOA | RK73H1ETTP1002F | 22 | G | PEUR1,PSRR6,R23,PHAR23,R119,R121,R131,R133,R138,R159,R162,R172,R174,R183,R185,R195,R197,R234,R1815,R1816,R1817,R1818 |  |  |  |  |  |  |
|  |  |  |  |  | 26 | 61010G500-012-G |  | RES,10KOhm,+/-1%,1/16W,G,SMD0402 | WALSIN | WR04X1002FTL |  | G |  |  |  |  |  |  |  |
|  |  |  |  |  | 26 | 61010G500-011-G |  | RES,10KOhm,+/-1%,1/16W,G,SMD0402 | YAGEO | RC0402FR-0710KL |  | G |  |  |  |  |  |  |  |
|  |  |  |  |  | 26 | 61010G500-044-G |  | RES,10KOhm,+/-1%,1/16W,G,SMD0402 | TA-I | RM04FTN1002 |  | G |  |  |  |  |  |  |  |
|  |  |  |  |  | 26 | 61010G500-029-G |  | RES,10KOhm,+/-1%,1/16W,G,SMD0402 | VISHAY | CRCW040210K0FKED |  | G |  |  |  |  |  |  |  |
|  |  |  |  |  | 26 | 61010G500-024-G |  | RES,10KOhm,+/-1%,1/16W,G,SMD0402 | PANASONIC | ERJ2RKF1002X |  | G |  |  |  |  |  |  |  |
|  |  |  |  | 27 | 27 | 610107A00-017-G | - | RES,0 Ohm,+/-5%,1/16W,G,SMD0402 | KOA | RK73Z1ETTP | 55 | G | R1,R9,PSRR9,R10,PHAR11,PHAR12,PSRR13,PSRR15,PSRR18,PHAR24,PHAR25,R30,R31,PHAR31,PHAR32,PHAR34,R51,R52,R123,R135,R139,R140,R161,R171,R199,R235,R494,R499,PSUR500,PEUR500,PSUR501,PEUR501,R1775,R1781,R1783,R1790,R1791,R1792,R1793,R1794,R1795,R1796,R1797,R1798,R1799,R1800,R1801,R1802,R1803,R1804,R1805,R1806,R1807,R1808,R1813 |  |  |  |  |  |  |
|  |  |  |  |  | 27 | 610107A00-012-G |  | RES,0 Ohm,+/-5%,1/16W,G,SMD0402 | WALSIN | WR04X000PTL |  | G |  |  |  |  |  |  |  |
|  |  |  |  |  | 27 | 610107A00-011-G |  | RES,0 Ohm,+/-5%,1/16W,G,SMD0402 | YAGEO | RC0402JR-070RL |  | G |  |  |  |  |  |  |  |
|  |  |  |  |  | 27 | 610107A00-044-G |  | RES,0 Ohm,+/-5%,1/16W,G,SMD0402 | TA-I | RM04JTN0 |  | G |  |  |  |  |  |  |  |
|  |  |  |  |  | 27 | 610107A00-024-G |  | RES,0 Ohm,+/-5%,1/16W,G,SMD0402 | PANASONIC | ERJ2GE0R00X |  | G |  |  |  |  |  |  |  |
|  |  |  |  |  | 27 | 610107A00-029-G |  | RES,0 Ohm,+/-5%,1/16W,G,SMD0402 | VISHAY | CRCW04020000Z0ED |  | G |  |  |  |  |  |  |  |
|  |  |  |  | 28 | 28 | 880302300-065-G |  | Converter,input 40V~60V,600W,G,Q54SJ12050NNDH | DELTA | Q54SJ12050NNDH | 2 | G | PSUU1,PEUU1 |  |  |  |  |  |  |
|  |  |  |  | 29 | 29 | 620131D00-015-G |  | CAP,1uF,+/-10%,X6S,16V,G,SMD0402 | MURATA | GRM155C81C105KE11J | 2 | G | PHAC1,PHAC7 |  |  |  |  |  |  |
|  |  |  |  |  | 29 | 620131D00-023-G |  | CAP,1uF,+/-10%,X6S,16V,G,SMD0402 | TAIYO | EMK105C6105KV-F |  | G |  |  |  |  |  |  |  |
|  |  |  |  | 30 | 30 | 620133600-015-G |  | CAP,1nF,+/-5%,X7R,100V,G,SMD0805 | MURATA | GRM219R72A102JA01D | 1 | G | PHAC3 |  |  |  |  |  |  |
|  |  |  |  |  | 30 | 620133600-012-G |  | CAP,1nF,+/-5%,X7R,100V,G,SMD0805 | WALSIN | 0805B102J101CT |  | G |  |  |  |  |  |  |  |
|  |  |  |  | 31 | 31 | 62010G800-015-G | - | CAP,22nF,+/-10%,X7R,16V,G,SMD0402 | MURATA | GRM155R71C223K | 1 | G | PHAC4 |  |  |  |  |  |  |
|  |  |  |  |  | 31 | 62010G800-012-G |  | CAP,22nF,+/-10%,X7R,16V,G,SMD0402 | WALSIN | 0402B223K160CT |  | G |  |  |  |  |  |  |  |
|  |  |  |  |  | 31 | 62010G800-026-G |  | CAP,22nF,+/-10%,X7R,16V,G,SMD0402 | SAMSUNG | CL05B223KO5NNNC |  | G |  |  |  |  |  |  |  |
|  |  |  |  |  | 31 | 62010G800-023-G |  | CAP,22nF,+/-10%,X7R,16V,G,SMD0402 | TAIYO | EMK105B7223KV-F |  | G |  |  |  |  |  |  |  |
|  |  |  |  | 32 | 32 | 62010VD00-015-G |  | CAP,100nF,+/-10%,X7R,100V,G,SMD0603 | MURATA | GRM188R72A104K | 2 | G | PHAC14,C2118 |  |  |  |  |  |  |
|  |  |  |  |  | 32 | 62010VD00-026-G |  | CAP,100nF,+/-10%,X7R,100V,G,SMD0603 | SAMSUNG | CL10B104KC8NNNC |  | G |  |  |  |  |  |  |  |
|  |  |  |  | 33 | 33 | 620135500-015-G |  | CAP,39nF,+/-10%,X7R,100V,G,SMD0805 | MURATA | GRM21BR72A393KA01L | 1 | G | PHAC18 |  |  |  |  |  |  |
|  |  |  |  |  | 33 | 620135500-012-G |  | CAP,39nF,+/-10%,X7R,100V,G,SMD0805 | WALSIN | 0805B393K101CT |  | G |  |  |  |  |  |  |  |
|  |  |  |  | 34 | 34 | 52170KE00-086-G |  | TVS Diode,SMCJ64A,G,DO-214AB-2,SMD | LITTELFUSE | SMCJ64A | 1 | G | PHAD1 |  |  |  |  |  |  |
|  |  |  |  | 35 | 35 | 52030YE00-223-G |  | DIODE,Schottky,MBR5H100MFST1G,100V,5A,G,SO8FL-8,SMD | ON | MBR5H100MFST1G | 1 | G | PHAD2 |  |  |  |  |  |  |
|  |  |  |  | 36 | 36 | 51031VY00-031-G |  | MOS N,PSMN4R8-100BSE,100V,120A,4.8m@10V,G,SOT404-3,SMD | NXP | PSMN4R8-100BSE | 3 | G | PHAQ1,PHAQ2,PHAQ3 |  |  |  |  |  |  |
|  |  |  |  | 37 | 37 | 51020A000-031-G |  | TRANS P,PBHV9115T,150V,1A,G,SOT23-3,SMD | NXP | PBHV9115T | 1 | G | PHAQ4 |  |  |  |  |  |  |
|  |  |  |  | 38 | 38 | 51032D100-237-G |  | MOS N,DMN10H220L-7,100V,1.6A,220m@10V,G,SOT-23-3,SMD | DIODES | DMN10H220L-7 | 2 | G | PHAQ5,PHAQ9 |  |  |  |  |  |  |
|  |  |  |  | 39 | 39 | 510100W00-237-G | - | TRANS N,MMBT3904-7-F,40V,0.2A,G,SOT23-3,SMD | DIODES | MMBT3904-7-F | 1 | G | PHAQ8 |  |  |  |  |  |  |
|  |  |  |  | 40 | 40 | 610602200-32D-G |  | RES,0.5mOhm,+/-1%,3W,G,SMD2512 | Thin Film Technology Corporation | CPA1225RR0005FW | 1 | G | PHAR1 |  |  |  |  |  |  |
|  |  |  |  | 41 | 41 | 61100DA00-017-G |  | RES,33KOhm,+/-0.1%,1/16W,G,SMD0402 | KOA | RN731ETTP3302B25 | 1 | G | PHAR2 |  |  |  |  |  |  |
|  |  |  |  |  | 41 | 61100DA00-012-G |  | RES,33KOhm,+/-0.1%,1/16W,G,SMD0402 | WALSIN | WF04U3302BTL |  | G |  |  |  |  |  |  |  |
|  |  |  |  |  | 41 | 61100DA00-011-G |  | RES,33KOhm,+/-0.1%,1/16W,G,SMD0402 | YAGEO | RT0402BRD0733KL |  | G |  |  |  |  |  |  |  |
|  |  |  |  | 42 | 42 | 610130Y00-017-G |  | RES,1 Ohm,+/-1%,1/3W,G,SMD1206 | KOA | SR732BTTD1R00F | 1 | G | PHAR4 |  |  |  |  |  |  |
|  |  |  |  |  | 42 | 610122P00-012-G |  | RES,1 Ohm,+/-1%,1/2W,G,SMD1206 | WALSIN | WF12P1R00FTL |  | G |  |  |  |  |  |  |  |
|  |  |  |  |  | 42 | 610122P00-011-G |  | RES,1 Ohm,+/-1%,1/2W,G,SMD1206 | YAGEO | RC1206FR-7W1RL |  | G |  |  |  |  |  |  |  |
|  |  |  |  |  | 42 | 610122P00-044-G |  | RES,1 Ohm,+/-1%,1/2W,G,SMD1206 | TA-I | RMH12FT1R00 |  | G |  |  |  |  |  |  |  |
|  |  |  |  | 43 | 43 | 61100QM00-017-G |  | RES,100KOhm,+/-0.1%,1/10W,G,SMD0603 | KOA | RN73H1JTTD1003B25 | 4 | G | PHAR5,PHAR7,PHAR40,PHAR45 |  |  |  |  |  |  |
|  |  |  |  |  | 43 | 61100QM00-012-G |  | RES,100KOhm,+/-0.1%,1/10W,G,SMD0603 | WALSIN | WF06Q1003BTL |  | G |  |  |  |  |  |  |  |
|  |  |  |  |  | 43 | 61100QM00-011-G |  | RES,100KOhm,+/-0.1%,1/10W,G,SMD0603 | YAGEO | RT0603BRD07100KL |  | G |  |  |  |  |  |  |  |
|  |  |  |  | 44 | 44 | 610100200-017-G | - | RES,7.5KOhm,+/-1%,1/10W,G,SMD0603 | KOA | RK73H1JTTD7501F | 1 | G | PHAR6 |  |  |  |  |  |  |
|  |  |  |  |  | 44 | 610100200-012-G |  | RES,7.5KOhm,+/-1%,1/10W,G,SMD0603 | WALSIN | WR06X7501FTL |  | G |  |  |  |  |  |  |  |
|  |  |  |  |  | 44 | 610100200-011-G |  | RES,7.5KOhm,+/-1%,1/10W,G,SMD0603 | YAGEO | RC0603FR-077K5L |  | G |  |  |  |  |  |  |  |
|  |  |  |  |  | 44 | 610100200-044-G |  | RES,7.5KOhm,+/-1%,1/10W,G,SMD0603 | TA-I | RM06FTN7501 |  | G |  |  |  |  |  |  |  |
|  |  |  |  | 45 | 45 | 610103Y00-017-G |  | RES,10 Ohm,+/-1%,1/10W,G,SMD0603 | KOA | RK73H1JTTD10R0F | 3 | G | PHAR8,PHAR14,PHAR15 |  |  |  |  |  |  |
|  |  |  |  |  | 45 | 610103Y00-011-G |  | RES,10 Ohm,+/-1%,1/10W,G,SMD0603 | YAGEO | RC0603FR-0710RL |  | G |  |  |  |  |  |  |  |
|  |  |  |  |  | 45 | 610103Y00-044-G |  | RES,10 Ohm,+/-1%,1/10W,G,SMD0603 | TA-I | RM06FTN10R0 |  | G |  |  |  |  |  |  |  |
|  |  |  |  |  | 45 | 610103Y00-012-G |  | RES,10 Ohm,+/-1%,1/10W,G,SMD0603 | WALSIN | WR06X10R0FTL |  | G |  |  |  |  |  |  |  |
|  |  |  |  |  | 45 | 610103Y00-024-G |  | RES,10 Ohm,+/-1%,1/10W,G,SMD0603 | PANASONIC | ERJ3EKF10R0V |  | G |  |  |  |  |  |  |  |
|  |  |  |  | 46 | 46 | 61010L300-017-G | - | RES,1KOhm,+/-1%,1/16W,G,SMD0402 | KOA | RK73H1ETTP1001F | 3 | G | PHAR9,PHAR38,R251 |  |  |  |  |  |  |
|  |  |  |  |  | 46 | 61010L300-012-G |  | RES,1KOhm,+/-1%,1/16W,G,SMD0402 | WALSIN | WR04X1001FTL |  | G |  |  |  |  |  |  |  |
|  |  |  |  |  | 46 | 61010L300-011-G |  | RES,1KOhm,+/-1%,1/16W,G,SMD0402 | YAGEO | RC0402FR-071KL |  | G |  |  |  |  |  |  |  |
|  |  |  |  |  | 46 | 61010L300-044-G |  | RES,1KOhm,+/-1%,1/16W,G,SMD0402 | TA-I | RM04FTN1001 |  | G |  |  |  |  |  |  |  |
|  |  |  |  |  | 46 | 61010L300-024-G |  | RES,1KOhm,+/-1%,1/16W,G,SMD0402 | PANASONIC | ERJ2RKF1001X |  | G |  |  |  |  |  |  |  |
|  |  |  |  |  | 46 | 61010L300-029-G |  | RES,1KOhm,+/-1%,1/16W,G,SMD0402 | VISHAY | CRCW04021K00FKED |  | G |  |  |  |  |  |  |  |
|  |  |  |  | 47 | 47 | 61013GW00-017-G |  | RES,150KOhm,+/-1%,1/8W,G,SMD0805 | KOA | RK73H2ATTD1503F | 1 | G | PHAR13 |  |  |  |  |  |  |
|  |  |  |  |  | 47 | 61013GW00-012-G |  | RES,150KOhm,+/-1%,1/8W,G,SMD0805 | WALSIN | WR08X1503FTL |  | G |  |  |  |  |  |  |  |
|  |  |  |  |  | 47 | 61013GW00-011-G |  | RES,150KOhm,+/-1%,1/8W,G,SMD0805 | YAGEO | RC0805FR-07150KL |  | G |  |  |  |  |  |  |  |
|  |  |  |  |  | 47 | 61013GW00-044-G |  | RES,150KOhm,+/-1%,1/8W,G,SMD0805 | TA-I | RM10FTN1503 |  | G |  |  |  |  |  |  |  |
|  |  |  |  | 48 | 48 | 610114F00-017-G | - | RES,3.16KOhm,+/-1%,1/16W,G,SMD0402 | KOA | RK73H1ETTP3161F | 1 | G | PHAR20 |  |  |  |  |  |  |
|  |  |  |  |  | 48 | 610114F00-012-G |  | RES,3.16KOhm,+/-1%,1/16W,G,SMD0402 | WALSIN | WR04X3161FTL |  | G |  |  |  |  |  |  |  |
|  |  |  |  |  | 48 | 610114F00-011-G |  | RES,3.16KOhm,+/-1%,1/16W,G,SMD0402 | YAGEO | RC0402FR-073K16L |  | G |  |  |  |  |  |  |  |
|  |  |  |  |  | 48 | 610114F00-044-G |  | RES,3.16KOhm,+/-1%,1/16W,G,SMD0402 | TA-I | RM04FTN3161 |  | G |  |  |  |  |  |  |  |
|  |  |  |  | 49 | 49 | 61011NM00-017-G |  | RES,6.81KOhm,+/-1%,1/16W,G,SMD0402 | KOA | RK73H1ETTP6811F | 1 | G | PHAR22 |  |  |  |  |  |  |
|  |  |  |  |  | 49 | 61011NM00-012-G |  | RES,6.81KOhm,+/-1%,1/16W,G,SMD0402 | WALSIN | WR04X6811FTL |  | G |  |  |  |  |  |  |  |
|  |  |  |  |  | 49 | 61011NM00-011-G |  | RES,6.81KOhm,+/-1%,1/16W,G,SMD0402 | YAGEO | RC0402FR-076K81L |  | G |  |  |  |  |  |  |  |
|  |  |  |  |  | 49 | 61011NM00-044-G |  | RES,6.81KOhm,+/-1%,1/16W,G,SMD0402 | TA-I | RM04FTN6811 |  | G |  |  |  |  |  |  |  |
|  |  |  |  | 50 | 50 | 61010LA00-017-G | - | RES,4.7KOhm,+/-1%,1/16W,G,SMD0402 | KOA | RK73H1ETTP4701F | 49 | G | R2,R3,R4,R8,R12,R13,R14,R18,R19,R20,R21,R22,R25,R26,R27,R28,PHAR28,R29,PHAR29,PHAR30,R34,R35,R36,R39,R40,R41,R42,R43,R46,R47,R48,R49,R50,R54,R55,R114,R115,R126,R127,R141,R154,R156,R169,R170,R178,R179,R190,R191,R501 |  |  |  |  |  |  |
|  |  |  |  |  | 50 | 61010LA00-012-G |  | RES,4.7KOhm,+/-1%,1/16W,G,SMD0402 | WALSIN | WR04X4701FTL |  | G |  |  |  |  |  |  |  |
|  |  |  |  |  | 50 | 61010LA00-011-G |  | RES,4.7KOhm,+/-1%,1/16W,G,SMD0402 | YAGEO | RC0402FR-074K7L |  | G |  |  |  |  |  |  |  |
|  |  |  |  |  | 50 | 61010LA00-044-G |  | RES,4.7KOhm,+/-1%,1/16W,G,SMD0402 | TA-I | RM04FTN4701 |  | G |  |  |  |  |  |  |  |
|  |  |  |  | 51 | 51 | 61011PE00-017-G |  | RES,8.87KOhm,+/-1%,1/16W,G,SMD0402 | KOA | RK73H1ETTP8871F | 1 | G | PHAR35 |  |  |  |  |  |  |
|  |  |  |  |  | 51 | 61011PE00-012-G |  | RES,8.87KOhm,+/-1%,1/16W,G,SMD0402 | WALSIN | WR04X8871FTL |  | G |  |  |  |  |  |  |  |
|  |  |  |  |  | 51 | 61011PE00-011-G |  | RES,8.87KOhm,+/-1%,1/16W,G,SMD0402 | YAGEO | RC0402FR-078K87L |  | G |  |  |  |  |  |  |  |
|  |  |  |  |  | 51 | 61011PE00-044-G |  | RES,8.87KOhm,+/-1%,1/16W,G,SMD0402 | TA-I | RM04FTN8871 |  | G |  |  |  |  |  |  |  |
|  |  |  |  | 52 | 52 | 61010BY00-017-G | - | RES,20KOhm,+/-1%,1/10W,G,SMD0603 | KOA | RK73H1JTTD2002F | 2 | G | PHAR42,PHAR46 |  |  |  |  |  |  |
|  |  |  |  |  | 52 | 61010BY00-012-G |  | RES,20KOhm,+/-1%,1/10W,G,SMD0603 | WALSIN | WR06X2002FTL |  | G |  |  |  |  |  |  |  |
|  |  |  |  |  | 52 | 61010BY00-011-G |  | RES,20KOhm,+/-1%,1/10W,G,SMD0603 | YAGEO | RC0603FR-0720KL |  | G |  |  |  |  |  |  |  |
|  |  |  |  |  | 52 | 61010BY00-044-G |  | RES,20KOhm,+/-1%,1/10W,G,SMD0603 | TA-I | RM06FTN2002 |  | G |  |  |  |  |  |  |  |
|  |  |  |  | 53 | 53 | 610107H00-017-G |  | RES,4.02KOhm,+/-1%,1/10W,G,SMD0603 | KOA | RK73H1JTTD4021F | 1 | G | PHAR44 |  |  |  |  |  |  |
|  |  |  |  |  | 53 | 610107H00-012-G |  | RES,4.02KOhm,+/-1%,1/10W,G,SMD0603 | WALSIN | WR06X4021FTL |  | G |  |  |  |  |  |  |  |
|  |  |  |  |  | 53 | 610107H00-011-G |  | RES,4.02KOhm,+/-1%,1/10W,G,SMD0603 | YAGEO | RC0603FR-074K02L |  | G |  |  |  |  |  |  |  |
|  |  |  |  |  | 53 | 610107H00-044-G |  | RES,4.02KOhm,+/-1%,1/10W,G,SMD0603 | TA-I | RM06FTN4021 |  | G |  |  |  |  |  |  |  |
|  |  |  |  | 54 | 54 | 32023RR00-183-G |  | IC,Power Controller,LM5066IPMHX/NOPB,G,HTSSOP-28,SMD | TI | LM5066IPMHX/NOPB | 1 | G | PHAU1 |  |  |  |  |  |  |
|  |  |  |  | 55 | 55 | 62012GG00-015-G |  | CAP,10uF,+/-10%,X7S,25V,G,SMD0805 | MURATA | GRM21BC71E106K | 1 | G | PSRC3 |  |  |  |  |  |  |
|  |  |  |  |  | 55 | 62012GG00-012-G |  | CAP,10uF,+/-10%,X7S,25V,G,SMD0805 | WALSIN | 0805A106K250CT |  | G |  |  |  |  |  |  |  |
|  |  |  |  | 56 | 56 | 62012T300-015-G |  | CAP,1uF,+/-10%,X7S,25V,G,SMD0402 | MURATA | GRM155C71E105KE11D | 1 | G | PSRC4 |  |  |  |  |  |  |
|  |  |  |  | 57 | 57 | 62012P100-015-G |  | CAP,2.2uF,+/-20%,X7S,10V,G,SMD0402 | MURATA | GRM155C71A225M | 1 | G | PSRC5 |  |  |  |  |  |  |
|  |  |  |  |  | 57 | 62012P100-012-G |  | CAP,2.2uF,+/-20%,X7S,10V,G,SMD0402 | WALSIN | 0402A225M100CT |  | G |  |  |  |  |  |  |  |
|  |  |  |  | 58 | 58 | 62012PT00-015-G |  | CAP,22uF,+/-20%,X6S,16V,G,SMD0805 | MURATA | GRM21BC81C226M | 5 | G | PSRC7,PSRC8,PSRC11,PSRC12,PSRC15 |  |  |  |  |  |  |
|  |  |  |  |  | 58 | 62012PT00-023-G |  | CAP,22uF,+/-20%,X6S,16V,G,SMD0805 | TAIYO | EDK212BC6226MG-T |  | G |  |  |  |  |  |  |  |
|  |  |  |  | 59 | 59 | 620105U00-015-G | - | CAP,220pF,+/-10%,X7R,50V,G,SMD0402 | MURATA | GRM155R71H221K | 1 | G | PSRC14 |  |  |  |  |  |  |
|  |  |  |  |  | 59 | 620105U00-012-G |  | CAP,220pF,+/-10%,X7R,50V,G,SMD0402 | WALSIN | 0402B221K500CT |  | G |  |  |  |  |  |  |  |
|  |  |  |  |  | 59 | 620105U00-026-G |  | CAP,220pF,+/-10%,X7R,50V,G,SMD0402 | SAMSUNG | CL05B221KB5NNNC |  | G |  |  |  |  |  |  |  |
|  |  |  |  | 60 | 60 | 62012H100-015-G |  | CAP,10uF,+/-20%,X6S,10V,G,SMD0603 | MURATA | GRM188C81A106M | 1 | G | PSRC16 |  |  |  |  |  |  |
|  |  |  |  |  | 60 | 62012H100-023-G |  | CAP,10uF,+/-20%,X6S,10V,G,SMD0603 | TAIYO | LMK107BC6106MA-T |  | G |  |  |  |  |  |  |  |
|  |  |  |  |  | 60 | 62012H100-026-G |  | CAP,10uF,+/-20%,X6S,10V,G,SMD0603 | SAMSUNG | CL10X106MP8NRNC |  | G |  |  |  |  |  |  |  |
|  |  |  |  | 61 | 61 | 72010RE00-015-G |  | FB,26 Ohm@100MHz,+/-25%,6A,7mOhm,G,SMD0603 | MURATA | BLM18KG260TN1D | 1 | G | PSRL1 |  |  |  |  |  |  |
|  |  |  |  |  | 61 | 72010SJ00-059-G |  | FB,26 Ohm@100MHz,+/-25%,6A,10mOhm,G,SMD0603 | TAI-TECH | HCB1608KF-260T60 |  | G |  |  |  |  |  |  |  |
|  |  |  |  | 62 | 62 | 63032PP00-088-G |  | IND,4.7uH@100KHz,+/-20%,5.5A,40mOhm,SHLD,G,SMD | COOPER | HCM0703-4R7-R | 1 | G | PSRL2 |  |  |  |  |  |  |
|  |  |  |  | 63 | 63 | 61011R400-017-G |  | RES,34.8KOhm,+/-1%,1/16W,G,SMD0402 | KOA | RK73H1ETTP3482F | 1 | G | PSRR1 |  |  |  |  |  |  |
|  |  |  |  |  | 63 | 61011R400-012-G |  | RES,34.8KOhm,+/-1%,1/16W,G,SMD0402 | WALSIN | WR04X3482FTL |  | G |  |  |  |  |  |  |  |
|  |  |  |  |  | 63 | 61011R400-011-G |  | RES,34.8KOhm,+/-1%,1/16W,G,SMD0402 | YAGEO | RC0402FR-0734K8L |  | G |  |  |  |  |  |  |  |
|  |  |  |  |  | 63 | 61011R400-044-G |  | RES,34.8KOhm,+/-1%,1/16W,G,SMD0402 | TA-I | RM04FTN3482 |  | G |  |  |  |  |  |  |  |
|  |  |  |  | 64 | 64 | 610114S00-017-G | - | RES,4.99KOhm,+/-1%,1/16W,G,SMD0402 | KOA | RK73H1ETTP4991F | 1 | G | PSRR3 |  |  |  |  |  |  |
|  |  |  |  |  | 64 | 610114S00-012-G |  | RES,4.99KOhm,+/-1%,1/16W,G,SMD0402 | WALSIN | WR04X4991FTL |  | G |  |  |  |  |  |  |  |
|  |  |  |  |  | 64 | 610114S00-011-G |  | RES,4.99KOhm,+/-1%,1/16W,G,SMD0402 | YAGEO | RC0402FR-074K99L |  | G |  |  |  |  |  |  |  |
|  |  |  |  |  | 64 | 610114S00-044-G |  | RES,4.99KOhm,+/-1%,1/16W,G,SMD0402 | TA-I | RM04FTN4991 |  | G |  |  |  |  |  |  |  |
|  |  |  |  |  | 64 | 610114S00-024-G |  | RES,4.99KOhm,+/-1%,1/16W,G,SMD0402 | PANASONIC | ERJ2RKF4991X |  | G |  |  |  |  |  |  |  |
|  |  |  |  | 65 | 65 | 61011HA00-017-G |  | RES,1 Ohm,+/-1%,1/16W,G,SMD0402 | KOA | RK73H1ETTP1R00F | 1 | G | PSRR5 |  |  |  |  |  |  |
|  |  |  |  |  | 65 | 61011HA00-012-G |  | RES,1 Ohm,+/-1%,1/16W,G,SMD0402 | WALSIN | WR04W1R00FTL |  | G |  |  |  |  |  |  |  |
|  |  |  |  |  | 65 | 61011HA00-011-G |  | RES,1 Ohm,+/-1%,1/16W,G,SMD0402 | YAGEO | RC0402FR-071RL |  | G |  |  |  |  |  |  |  |
|  |  |  |  |  | 65 | 61011HA00-044-G |  | RES,1 Ohm,+/-1%,1/16W,G,SMD0402 | TA-I | RM04FTN1R00 |  | G |  |  |  |  |  |  |  |
|  |  |  |  |  | 65 | 61011HA00-029-G |  | RES,1 Ohm,+/-1%,1/16W,G,SMD0402 | VISHAY | CRCW04021R00FNED |  | G |  |  |  |  |  |  |  |
|  |  |  |  | 66 | 66 | 611004M00-017-G |  | RES,16.5KOhm,+/-0.1%,1/16W,G,SMD0402 | KOA | RN731ETTP1652B25 | 1 | G | PSRR17 |  |  |  |  |  |  |
|  |  |  |  |  | 66 | 611004M00-024-G |  | RES,16.5KOhm,+/-0.1%,1/16W,G,SMD0402 | PANASONIC | ERA2AEB1652X |  | G |  |  |  |  |  |  |  |
|  |  |  |  | 67 | 67 | 61100YB00-017-G |  | RES,2.94KOhm,+/-0.1%,1/16W,G,SMD0402 | KOA | RN731ETTP2941B25 | 1 | G | PSRR19 |  |  |  |  |  |  |
|  |  |  |  | 68 | 68 | 32013PD00-238-G |  | IC,Regulator,IR3883MTRPbF,ADJ,3A,G,QFN-16,SMD | IR | IR3883MTRPBF | 1 | G | PSRU1 |  |  |  |  |  |  |
|  |  |  |  | 69 | 69 | 610115R00-017-G |  | RES,15KOhm,+/-1%,1/16W,G,SMD0402 | KOA | RK73H1ETTP1502F | 1 | G | PSUR1 |  |  |  |  |  |  |
|  |  |  |  |  | 69 | 610115R00-012-G |  | RES,15KOhm,+/-1%,1/16W,G,SMD0402 | WALSIN | WR04X1502FTL |  | G |  |  |  |  |  |  |  |
|  |  |  |  |  | 69 | 610115R00-011-G |  | RES,15KOhm,+/-1%,1/16W,G,SMD0402 | YAGEO | RC0402FR-0715KL |  | G |  |  |  |  |  |  |  |
|  |  |  |  |  | 69 | 610115R00-044-G |  | RES,15KOhm,+/-1%,1/16W,G,SMD0402 | TA-I | RM04FTN1502 |  | G |  |  |  |  |  |  |  |
|  |  |  |  |  | 69 | 610115R00-024-G |  | RES,15KOhm,+/-1%,1/16W,G,SMD0402 | PANASONIC | ERJ2RKF1502X |  | G |  |  |  |  |  |  |  |
|  |  |  |  |  | 69 | 610115R00-029-G |  | RES,15KOhm,+/-1%,1/16W,G,SMD0402 | VISHAY | CRCW040215K0FKED |  | G |  |  |  |  |  |  |  |
|  |  |  |  | 70 | 70 | 510503B00-223-G |  | MOS N/N,NTZD3154NT1G,20V,0.54A,550m24.5V,G,SOT563-6,SMD | ON | NTZD3154NT1G | 1 | G | QN4 |  |  |  |  |  |  |
|  |  |  |  |  | 70 | 51050C700-237-G |  | MOS N/N,DMN2400UV-7,20V,1.33A/0.84A,350m@4.5V,G,SOT563-6,SMD | DIODES | DMN2400UV-7 |  | G |  |  |  |  |  |  |  |
|  |  |  |  |  | 70 | 51050AK00-030-G |  | MOS N/N,EM6K6T2R,20V,0.3A,1ohm@4V,G,EMT-6,SMD | ROHM | EM6K6T2R |  | G |  |  |  |  |  |  |  |
|  |  |  |  | 71 | 71 | 510301D00-223-G |  | MOS N,BSS138LT1G,50V,0.2A,3.5ohm@5V,G,SOT23-3,SMD | ON | BSS138LT1G | 12 | G | Q1,Q2,Q3,Q4,Q5,Q6,Q7,Q8,Q9,Q10,Q11,Q12 |  |  |  |  |  |  |
|  |  |  |  |  | 71 | 510302R00-185-G |  | MOS N,BSS138,50V,0.22A,6ohm@4.5V,G,SOT23-3,SMD | FAIRCHILD | BSS138 |  | G |  |  |  |  |  |  |  |
|  |  |  |  |  | 71 | 510309C00-237-G |  | MOS N,BSS138-7-F,50V,0.2A,3.5ohm@10V,G,SOT23-3,SMD | DIODES | BSS138-7-F |  | G |  |  |  |  |  |  |  |
|  |  |  |  |  | 71 | 51030A800-221-G |  | MOS N,BSS138N,60V,0.23A,6ohm@4.5V,G,SOT23-3,SMD | INFINEON | BSS138N |  | G |  |  |  |  |  |  |  |
|  |  |  |  | 72 | 72 | 51040EK00-185-G |  | MOS P,FDMS6681Z,30V,49A,5m@4.5V,G,Power56-8,SMD | FAIRCHILD | FDMS6681Z | 2 | G | Q13,Q14 |  |  |  |  |  |  |
|  |  |  |  | 73 | 73 | 61010H800-017-G |  | RES,5.11 Ohm,+/-1%,1/10W,G,SMD0603 | KOA | RK73H1JTTD5R11F | 2 | G | R11,R32 |  |  |  |  |  |  |
|  |  |  |  |  | 73 | 61010H800-012-G |  | RES,5.11 Ohm,+/-1%,1/10W,G,SMD0603 | WALSIN | WR06W5R11FTL |  | G |  |  |  |  |  |  |  |
|  |  |  |  |  | 73 | 61010H800-011-G |  | RES,5.11 Ohm,+/-1%,1/10W,G,SMD0603 | YAGEO | RC0603FR-075R11L |  | G |  |  |  |  |  |  |  |
|  |  |  |  |  | 73 | 61010H800-044-G |  | RES,5.11 Ohm,+/-1%,1/10W,G,SMD0603 | TA-I | RM06FTN5R11 |  | G |  |  |  |  |  |  |  |
|  |  |  |  | 74 | 74 | 61011MQ00-017-G | - | RES,4.75KOhm,+/-1%,1/16W,G,SMD0402 | KOA | RK73H1ETTP4751F | 4 | G | R15,R33,R1772,R1814 |  |  |  |  |  |  |
|  |  |  |  |  | 74 | 61011MQ00-012-G |  | RES,4.75KOhm,+/-1%,1/16W,G,SMD0402 | WALSIN | WR04X4751FTL |  | G |  |  |  |  |  |  |  |
|  |  |  |  |  | 74 | 61011MQ00-011-G |  | RES,4.75KOhm,+/-1%,1/16W,G,SMD0402 | YAGEO | RC0402FR-074K75L |  | G |  |  |  |  |  |  |  |
|  |  |  |  |  | 74 | 61011MQ00-044-G |  | RES,4.75KOhm,+/-1%,1/16W,G,SMD0402 | TA-I | RM04FTN4751 |  | G |  |  |  |  |  |  |  |
|  |  |  |  | 75 | 75 | 610115J00-017-G | - | RES,33 Ohm,+/-1%,1/16W,G,SMD0402 | KOA | RK73H1ETTP33R0F | 2 | G | R17,R37 |  |  |  |  |  |  |
|  |  |  |  |  | 75 | 610115J00-012-G |  | RES,33 Ohm,+/-1%,1/16W,G,SMD0402 | WALSIN | WR04X33R0FTL |  | G |  |  |  |  |  |  |  |
|  |  |  |  |  | 75 | 610115J00-011-G |  | RES,33 Ohm,+/-1%,1/16W,G,SMD0402 | YAGEO | RC0402FR-0733RL |  | G |  |  |  |  |  |  |  |
|  |  |  |  |  | 75 | 610115J00-044-G |  | RES,33 Ohm,+/-1%,1/16W,G,SMD0402 | TA-I | RM04FTN33R0 |  | G |  |  |  |  |  |  |  |
|  |  |  |  |  | 75 | 610115J00-024-G |  | RES,33 Ohm,+/-1%,1/16W,G,SMD0402 | PANASONIC | ERJ2RKF33R0X |  | G |  |  |  |  |  |  |  |
|  |  |  |  | 76 | 76 | 61010L100-017-G | - | RES,100KOhm,+/-1%,1/16W,G,SMD0402 | KOA | RK73H1ETTP1003F | 3 | G | R45,R233,R236 |  |  |  |  |  |  |
|  |  |  |  |  | 76 | 61010L100-012-G |  | RES,100KOhm,+/-1%,1/16W,G,SMD0402 | WALSIN | WR04X1003FTL |  | G |  |  |  |  |  |  |  |
|  |  |  |  |  | 76 | 61010L100-011-G |  | RES,100KOhm,+/-1%,1/16W,G,SMD0402 | YAGEO | RC0402FR-07100KL |  | G |  |  |  |  |  |  |  |
|  |  |  |  |  | 76 | 61010L100-044-G |  | RES,100KOhm,+/-1%,1/16W,G,SMD0402 | TA-I | RM04FTN1003 |  | G |  |  |  |  |  |  |  |
|  |  |  |  |  | 76 | 61010L106-029-G |  | RES,100KOhm,+/-1%,1/16W,G,SMD0402 | VISHAY | CRCW0402100KFKEDC |  | G |  |  |  |  |  |  |  |
|  |  |  |  |  | 76 | 61010L100-024-G |  | RES,100KOhm,+/-1%,1/16W,G,SMD0402 | PANASONIC | ERJ2RKF1003X |  | G |  |  |  |  |  |  |  |
|  |  |  |  | 77 | 77 | 610103300-017-G | - | RES,100KOhm,+/-5%,1/16W,G,SMD0402 | KOA | RK73B1ETTP104J | 18 | G | R58,R60,R62,R64,R66,R68,R72,R74,R76,R78,R80,R82,R86,R88,R90,R92,R94,R96 |  |  |  |  |  |  |
|  |  |  |  |  | 77 | 610103300-012-G |  | RES,100KOhm,+/-5%,1/16W,G,SMD0402 | WALSIN | WR04X104JTL |  | G |  |  |  |  |  |  |  |
|  |  |  |  |  | 77 | 610103300-011-G |  | RES,100KOhm,+/-5%,1/16W,G,SMD0402 | YAGEO | RC0402JR-07100KL |  | G |  |  |  |  |  |  |  |
|  |  |  |  |  | 77 | 610103300-044-G |  | RES,100KOhm,+/-5%,1/16W,G,SMD0402 | TA-I | RM04JTN104 |  | G |  |  |  |  |  |  |  |
|  |  |  |  |  | 77 | 610103300-029-G |  | RES,100KOhm,+/-5%,1/16W,G,SMD0402 | VISHAY | CRCW0402100KJNED |  | G |  |  |  |  |  |  |  |
|  |  |  |  | 78 | 78 | 61011DR00-017-G |  | RES,2.2KOhm,+/-1%,1/16W,G,SMD0402 | KOA | RK73H1ETTP2201F | 24 | G | R59,R61,R73,R75,R87,R89,R116,R117,R118,R128,R129,R130,R155,R157,R158,R166,R167,R168,R180,R181,R182,R192,R193,R194 |  |  |  |  |  |  |
|  |  |  |  |  | 78 | 61011DR00-012-G |  | RES,2.2KOhm,+/-1%,1/16W,G,SMD0402 | WALSIN | WR04X2201FTL |  | G |  |  |  |  |  |  |  |
|  |  |  |  |  | 78 | 61011DR00-011-G |  | RES,2.2KOhm,+/-1%,1/16W,G,SMD0402 | YAGEO | RC0402FR-072K2L |  | G |  |  |  |  |  |  |  |
|  |  |  |  |  | 78 | 61011DR00-044-G |  | RES,2.2KOhm,+/-1%,1/16W,G,SMD0402 | TA-I | RM04FTN2201 |  | G |  |  |  |  |  |  |  |
|  |  |  |  |  | 78 | 61011DR00-029-G |  | RES,2.2KOhm,+/-1%,1/16W,G,SMD0402 | VISHAY | CRCW04022K20FKED |  | G |  |  |  |  |  |  |  |
|  |  |  |  | 79 | 79 | 61011DG01-017-G | - | RES,10KOhm,+/-1%,1/20W,G,SMD0201 | KOA | RK73H1HTTC1002F | 6 | G | R98,R99,R106,R107,R110,R112 |  |  |  |  |  |  |
|  |  |  |  |  | 79 | 61011DG00-012-G |  | RES,10KOhm,+/-1%,1/20W,G,SMD0201 | WALSIN | WR02X1002FAL |  | G |  |  |  |  |  |  |  |
|  |  |  |  |  | 79 | 61011DG00-011-G |  | RES,10KOhm,+/-1%,1/20W,G,SMD0201 | YAGEO | RC0201FR-0710KL |  | G |  |  |  |  |  |  |  |
|  |  |  |  |  | 79 | 61011DG00-044-G |  | RES,10KOhm,+/-1%,1/20W,G,SMD0201 | TA-I | RM02FTN1002 |  | G |  |  |  |  |  |  |  |
|  |  |  |  | 80 | 80 | 61011DL01-017-G | - | RES,1KOhm,+/-1%,1/20W,G,SMD0201 | KOA | RK73H1HTTC1001F | 2 | G | R100,R102 |  |  |  |  |  |  |
|  |  |  |  |  | 80 | 61011DL00-012-G |  | RES,1KOhm,+/-1%,1/20W,G,SMD0201 | WALSIN | WR02X1001FAL |  | G |  |  |  |  |  |  |  |
|  |  |  |  |  | 80 | 61011DL00-011-G |  | RES,1KOhm,+/-1%,1/20W,G,SMD0201 | YAGEO | RC0201FR-071KL |  | G |  |  |  |  |  |  |  |
|  |  |  |  |  | 80 | 61011DL00-044-G |  | RES,1KOhm,+/-1%,1/20W,G,SMD0201 | TA-I | RM02FTN1001 |  | G |  |  |  |  |  |  |  |
|  |  |  |  | 81 | 81 | 61010AN00-017-G |  | RES,1MOhm,+/-5%,1/16W,G,SMD0402 | KOA | RK73B1ETTP105J | 2 | G | R101,R103 |  |  |  |  |  |  |
|  |  |  |  |  | 81 | 61010AN00-012-G |  | RES,1MOhm,+/-5%,1/16W,G,SMD0402 | WALSIN | WR04X105JTL |  | G |  |  |  |  |  |  |  |
|  |  |  |  |  | 81 | 61010AN00-011-G |  | RES,1MOhm,+/-5%,1/16W,G,SMD0402 | YAGEO | RC0402JR-071ML |  | G |  |  |  |  |  |  |  |
|  |  |  |  |  | 81 | 61010AN00-044-G |  | RES,1MOhm,+/-5%,1/16W,G,SMD0402 | TA-I | RM04JTN105 |  | G |  |  |  |  |  |  |  |
|  |  |  |  | 82 | 82 | 610132800-017-G |  | RES,1.54KOhm,+/-1%,1/20W,G,SMD0201 | KOA | RK73H1HTTC1541F | 2 | G | R104,R105 |  |  |  |  |  |  |
|  |  |  |  |  | 82 | 610132800-012-G |  | RES,1.54KOhm,+/-1%,1/20W,G,SMD0201 | WALSIN | WR02X1541FAL |  | G |  |  |  |  |  |  |  |
|  |  |  |  |  | 82 | 610132800-044-G |  | RES,1.54KOhm,+/-1%,1/20W,G,SMD0201 | TA-I | RM02FTN1541 |  | G |  |  |  |  |  |  |  |
|  |  |  |  | 83 | 83 | 610113T00-017-G | - | RES,13.7KOhm,+/-1%,1/16W,G,SMD0402 | KOA | RK73H1ETTP1372F | 2 | G | R108,R109 |  |  |  |  |  |  |
|  |  |  |  |  | 83 | 610113T00-012-G |  | RES,13.7KOhm,+/-1%,1/16W,G,SMD0402 | WALSIN | WR04X1372FTL |  | G |  |  |  |  |  |  |  |
|  |  |  |  |  | 83 | 610113T00-011-G |  | RES,13.7KOhm,+/-1%,1/16W,G,SMD0402 | YAGEO | RC0402FR-0713K7L |  | G |  |  |  |  |  |  |  |
|  |  |  |  |  | 83 | 610113T00-044-G |  | RES,13.7KOhm,+/-1%,1/16W,G,SMD0402 | TA-I | RM04FTN1372 |  | G |  |  |  |  |  |  |  |
|  |  |  |  | 84 | 84 | 61011KY00-017-G |  | RES,3.83KOhm,+/-1%,1/16W,G,SMD0402 | KOA | RK73H1ETTP3831F | 2 | G | R111,R113 |  |  |  |  |  |  |
|  |  |  |  |  | 84 | 61011KY00-012-G |  | RES,3.83KOhm,+/-1%,1/16W,G,SMD0402 | WALSIN | WR04X3831FTL |  | G |  |  |  |  |  |  |  |
|  |  |  |  |  | 84 | 61011KY00-011-G |  | RES,3.83KOhm,+/-1%,1/16W,G,SMD0402 | YAGEO | RC0402FR-073K83L |  | G |  |  |  |  |  |  |  |
|  |  |  |  |  | 84 | 61011KY00-044-G |  | RES,3.83KOhm,+/-1%,1/16W,G,SMD0402 | TA-I | RM04FTN3831 |  | G |  |  |  |  |  |  |  |
|  |  |  |  |  | 84 | 61011KY00-029-G |  | RES,3.83KOhm,+/-1%,1/16W,G,SMD0402 | VISHAY | CRCW04023K83FKED |  | G |  |  |  |  |  |  |  |
|  |  |  |  | 85 | 85 | 61100LR00-017-G |  | RES,100 Ohm,+/-1%,1/16W,G,SMD0402 | KOA | RN731ETTP1000F50 | 14 | G | R120,R122,R132,R134,R160,R163,R173,R175,R184,R186,R196,R198,R500,R1779 |  |  |  |  |  |  |
|  |  |  |  |  | 85 | 61100LR00-012-G |  | RES,100 Ohm,+/-1%,1/16W,G,SMD0402 | WALSIN | WF04T1000FTL |  | G |  |  |  |  |  |  |  |
|  |  |  |  |  | 85 | 61100LR01-011-G |  | RES,100 Ohm,+/-1%,1/16W,G,SMD0402 | YAGEO | RT0402FRE07100RL |  | G |  |  |  |  |  |  |  |
|  |  |  |  |  | 85 | 61100LR00-044-G |  | RES,100 Ohm,+/-1%,1/16W,G,SMD0402 | TA-I | RB04FTS1000 |  | G |  |  |  |  |  |  |  |
|  |  |  |  | 86 | 86 | 61011CY00-017-G |  | RES,5.6KOhm,+/-1%,1/16W,G,SMD0402 | KOA | RK73H1ETTP5601F | 12 | G | R124,R125,R136,R137,R164,R165,R176,R177,R188,R189,R200,R201 |  |  |  |  |  |  |
|  |  |  |  |  | 86 | 61011CY00-012-G |  | RES,5.6KOhm,+/-1%,1/16W,G,SMD0402 | WALSIN | WR04X5601FTL |  | G |  |  |  |  |  |  |  |
|  |  |  |  |  | 86 | 61011CY00-011-G |  | RES,5.6KOhm,+/-1%,1/16W,G,SMD0402 | YAGEO | RC0402FR-075K6L |  | G |  |  |  |  |  |  |  |
|  |  |  |  |  | 86 | 61011CY00-044-G |  | RES,5.6KOhm,+/-1%,1/16W,G,SMD0402 | TA-I | RM04FTN5601 |  | G |  |  |  |  |  |  |  |
|  |  |  |  |  | 86 | 61011CY00-029-G |  | RES,5.6KOhm,+/-1%,1/16W,G,SMD0402 | VISHAY | CRCW04025K60FKED |  | G |  |  |  |  |  |  |  |
|  |  |  |  | 87 | 87 | 61011QD00-017-G | - | RES,330 Ohm,+/-1%,1/16W,G,SMD0402 | KOA | RK73H1ETTP3300F | 12 | G | R142,R143,R144,R145,R146,R147,R148,R149,R150,R151,R152,R153 |  |  |  |  |  |  |
|  |  |  |  |  | 87 | 61011QD00-012-G |  | RES,330 Ohm,+/-1%,1/16W,G,SMD0402 | WALSIN | WR04X3300FTL |  | G |  |  |  |  |  |  |  |
|  |  |  |  |  | 87 | 61011QD00-011-G |  | RES,330 Ohm,+/-1%,1/16W,G,SMD0402 | YAGEO | RC0402FR-07330RL |  | G |  |  |  |  |  |  |  |
|  |  |  |  |  | 87 | 61011QD00-044-G |  | RES,330 Ohm,+/-1%,1/16W,G,SMD0402 | TA-I | RM04FTN3300 |  | G |  |  |  |  |  |  |  |
|  |  |  |  | 88 | 88 | 61011H500-017-G | - | RES,22 Ohm,+/-1%,1/16W,G,SMD0402 | KOA | RK73H1ETTP22R0F | 1 | G | R202 |  |  |  |  |  |  |
|  |  |  |  |  | 88 | 61011H500-012-G |  | RES,22 Ohm,+/-1%,1/16W,G,SMD0402 | WALSIN | WR04X22R0FTL |  | G |  |  |  |  |  |  |  |
|  |  |  |  |  | 88 | 61011H500-011-G |  | RES,22 Ohm,+/-1%,1/16W,G,SMD0402 | YAGEO | RC0402FR-0722RL |  | G |  |  |  |  |  |  |  |
|  |  |  |  |  | 88 | 61011H500-044-G |  | RES,22 Ohm,+/-1%,1/16W,G,SMD0402 | TA-I | RM04FTN22R0 |  | G |  |  |  |  |  |  |  |
|  |  |  |  |  | 88 | 61011H500-024-G |  | RES,22 Ohm,+/-1%,1/16W,G,SMD0402 | PANASONIC | ERJ2RKF22R0X |  | G |  |  |  |  |  |  |  |
|  |  |  |  | 89 | 89 | 61010JY00-017-G | - | RES,220 Ohm,+/-5%,1/16W,G,SMD0402 | KOA | RK73B1ETTP221J | 18 | G | R203,R252,R253,R254,R255,R256,R257,R258,R260,R261,R262,R263,R264,R265,R266,R267,R1770,R1771 |  |  |  |  |  |  |
|  |  |  |  |  | 89 | 61010JY00-012-G |  | RES,220 Ohm,+/-5%,1/16W,G,SMD0402 | WALSIN | WR04X221JTL |  | G |  |  |  |  |  |  |  |
|  |  |  |  |  | 89 | 61010JY00-011-G |  | RES,220 Ohm,+/-5%,1/16W,G,SMD0402 | YAGEO | RC0402JR-07220RL |  | G |  |  |  |  |  |  |  |
|  |  |  |  |  | 89 | 61010JY00-044-G |  | RES,220 Ohm,+/-5%,1/16W,G,SMD0402 | TA-I | RM04JTN221 |  | G |  |  |  |  |  |  |  |
|  |  |  |  | 90 | 90 | 61011CM00-017-G | - | RES,69.8KOhm,+/-1%,1/16W,G,SMD0402 | KOA | RK73H1ETTP6982F | 3 | G | R1809,R1810,R1812 |  |  |  |  |  |  |
|  |  |  |  |  | 90 | 61011CM00-012-G |  | RES,69.8KOhm,+/-1%,1/16W,G,SMD0402 | WALSIN | WR04X6982FTL |  | G |  |  |  |  |  |  |  |
|  |  |  |  |  | 90 | 61011CM00-011-G |  | RES,69.8KOhm,+/-1%,1/16W,G,SMD0402 | YAGEO | RC0402FR-0769K8L |  | G |  |  |  |  |  |  |  |
|  |  |  |  |  | 90 | 61011CM00-044-G |  | RES,69.8KOhm,+/-1%,1/16W,G,SMD0402 | TA-I | RM04FTN6982 |  | G |  |  |  |  |  |  |  |
|  |  |  |  | 91 | 91 | 610113W00-017-G |  | RES,12.1KOhm,+/-1%,1/16W,G,SMD0402 | KOA | RK73H1ETTP1212F | 1 | G | R1811 |  |  |  |  |  |  |
|  |  |  |  |  | 91 | 610113W00-012-G |  | RES,12.1KOhm,+/-1%,1/16W,G,SMD0402 | WALSIN | WR04X1212FTL |  | G |  |  |  |  |  |  |  |
|  |  |  |  |  | 91 | 610113W00-011-G |  | RES,12.1KOhm,+/-1%,1/16W,G,SMD0402 | YAGEO | RC0402FR-0712K1L |  | G |  |  |  |  |  |  |  |
|  |  |  |  |  | 91 | 610113W00-044-G |  | RES,12.1KOhm,+/-1%,1/16W,G,SMD0402 | TA-I | RM04FTN1212 |  | G |  |  |  |  |  |  |  |
|  |  |  |  | 92 | 92 | 41040HW00-191-G |  | EEPROM,AT24C02D-SSHM-T,1.7~3.6V,2K,I2C,G,SOIC-8,SMD | ATMEL | AT24C02D-SSHM-T | 1 | G | U_FPDB_FRU |  |  |  |  |  |  |
|  |  |  |  |  | 92 | 410401W00-214-G |  | EEPROM,M24C02-WMN6TP,2.5~5.5V,256*8,I2C,G,SOIC-8,SMD | ST | M24C02-WMN6TP |  | G |  |  |  |  |  |  |  |
|  |  |  |  |  | 92 | 41040CW00-232-G |  | EEPROM,24AA024-I/SN,1.7~5.5V,2K,I2C,G,SOIC-8,SMD | MICROCHIP | 24AA024-I/SN |  | G |  |  |  |  |  |  |  |
|  |  |  |  | 93 | 93 | 320403K00-183-G | - | IC,Temp Sensor,TMP75AIDR,3°C,G,SOIC-8,SMD | TI | TMP75AIDR | 1 | G | U_TMP_R |  |  |  |  |  |  |
|  |  |  |  |  | 93 | 320404J00-190-G |  | IC,Temp Sensor,ADT75ARZ-REEL,1°C,G,SOIC-8,SMD | ANALOG DEVICES INC | ADT75ARZ-REEL |  | G |  |  |  |  |  |  |  |
|  |  |  |  | 94 | 94 | 311004800-031-G |  | IC,Translator,PCA9617ADPJ,0.8~5.5V,2.2~5.5V,G,TSSOP-8,SMD | NXP | PCA9617ADPJ | 1 | G | U1 |  |  |  |  |  |  |
|  |  |  |  |  | 94 | 311004V00-223-G |  | Logic IC,Translator,PCA9617ADMR2G,Vcca=0.8V~5.5V,Vccb=2.2V~5.5V,102ns,Micro8,8P,G | ON | PCA9617ADMR2G |  | G |  |  |  |  |  |  |  |
|  |  |  |  |  | 94 | 311004K00-183-G |  | Logic IC,Translator,TCA9617ADGKR,Vcca=0.8V~5.5V;Vccb=2.2V~5.5V,250ns,VSSOP,8P,G | TI | TCA9617ADGKR |  | G |  |  |  |  |  |  |  |
|  |  |  |  |  | 94 | 311004U00-252-G |  | Logic IC,Translator,PI6ULS5V9617AUEX,Vcca=0.8V~5.5V,Vccb=2.2V~5.5V,102ns,MSOP,8P,G | PERICOM | PI6ULS5V9617AUEX |  | G |  |  |  |  |  |  |  |
|  |  |  |  | 95 | 95 | 310204100-183-G | - | IC,Gate&Inverter,SN74LVC1G14DCKR,1.65~5.5V,G,SC70-5,SMD | TI | SN74LVC1G14DCKR | 1 | G | U2 |  |  |  |  |  |  |
|  |  |  |  | 96 | 96 | 32040QL00-09N-G |  | IC,Temp Sensor,A,NCT7904D,N/A,G,LQFP-48,SMD | Nuvoton | NCT7904D | 2 | G | U3,U4 |  |  |  |  |  |  |
|  |  |  |  | 97 | 97 | 31010DT00-031-G |  | IC,Gate,74LVC1G02GW,1.65~5.5V,G,SC88A-5,SMD | NXP | 74LVC1G02GW | 1 | G | U5 |  |  |  |  |  |  |
|  |  |  |  | 98 | 98 | 310502800-031-G |  | IC,Buffer,74LVC1G07GW,1.65~5.5V,G,SOT353-5,SMD | NXP | 74LVC1G07GW | 8 | G | U6,U8,U19,U20,U21,U22,U23,U24 |  |  |  |  |  |  |
|  |  |  |  | 99 | 99 | 31010SB00-183-G |  | Logic IC,Gate,ISO1540DR,3V~5.5V,G,SOIC-8,SMD | TI | ISO1540DR | 1 | G | U7 |  |  |  |  |  |  |
|  |  |  |  | 100 | 100 | 32022DM00-09N-G |  | IC,Power Controller,NCT7368S,G,SOP-8,SMD | Nuvoton | NCT7368S | 6 | G | U9,U10,U11,U12,U13,U14 |  |  |  |  |  |  |
|  |  |  |  | 101 | 101 | 310500U00-183-G | - | IC,Buffer,SN74LVC07APWR,1.65~5V,G,TSSOP-14,SMD | TI | SN74LVC07APWR | 1 | G | U15 |  |  |  |  |  |  |
|  |  |  |  | 102 | 102 | 320306E00-183-G |  | IC,Comparator,LMV331IDBVR,9mV,G,SOT23-5,SMD | TI | LMV331IDBVR | 2 | G | U16,U17 |  |  |  |  |  |  |
|  |  |  |  | 103 | 103 | 210204300-031-G |  | IC,NXP,PCA9535PW,G,TSSOP-24,SMD | NXP | PCA9535PW | 1 | G | U18 |  |  |  |  |  |  |
|  |  |  |  | 104 | 104 | 310200R00-183-G | - | IC,Trigger,SN74LV164ADBR,2~5.5V,G,SSOP-14,SMD | TI | SN74LV164ADBR | 2 | G | U25,U26 |  |  |  |  |  |  |
|  |  |  |  | 105 | 105 | 71020KL00-100-G | - | OSC,33MHz,+/-50ppm,3.3V,15pF,G,SMD | TXC | 7X33000013 | 2 | G | Y1,Y2 |  |  |  |  |  |  |
|  |  |  |  | 106 | 106 | 340636700-600-G |  | CONN,Header,Power,2X8,V/T,Whi,4.2mm,G,DIP-16 | FOXCONN | HM3508E-HP1 | 1 | G | J_EXP_PWR1 |  |  |  |  |  |  |
|  |  |  |  | 107 | 107 | 340636800-600-G |  | CONN,Header,Power,2X9,V/T,Whi,4.2mm,G,DIP-18 | FOXCONN | HM3509E-HP1 | 1 | G | J_GPU_PWR1 |  |  |  |  |  |  |
|  |  |  |  | 108 | 108 | 340612R00-309-G | - | CONN,Jumper,Bla,2.54mm,G,DIP-2 | SAMTEC | SNT-100-BK-G | 1 | G | J_PS_ON_SW(2-3)1 |  |  |  |  |  |  |
|  |  |  |  |  | 108 | 34065L900-GRT-G |  | CONN,jumper,Bla,2.54mm,30u,G,DIP-2 | PINREX | 201-71-01DB00 |  | G |  |  |  |  |  |  |  |
|  |  |  |  | 109 | 109 | 340600S00-600-G | - | CONN,Pin Header,1X3,V/T,Bla,2.54mm,15u,G,DIP-3 | FOXCONN | HB1103V | 1 | G | J_PS_ON1 |  |  |  |  |  |  |
|  |  |  |  |  | 109 | 34060WK00-317-G |  | CONN.Pin Header,1X3,V/T,Bla,2.54mm,15u,G,DIP-3 | MOLEX | 87891-0304 |  | G |  |  |  |  |  |  |  |
|  |  |  |  |  | 109 | 34065R700-GRT-G |  | CONN,Pin Header,1X3,V/T,Bla,2.54mm,15u,G,DIP-3 | PINREX | 21K-81-03HB01 |  | G |  |  |  |  |  |  |  |
|  |  |  |  |  | 109 | 34065RR00-245-G |  | CONN,Pin Header,1X3,V/T,Bla,2.54mm,15u,G,DIP-3 | AMPHENOL | G800305005EU |  | G |  |  |  |  |  |  |  |
|  |  |  |  | 110 | 110 | 34044PP00-G78-G |  | CONN,I/O,Terminal Blocks,R/A,Bla,4mm,G,DIP-4 | FCI | VP02650700J0G | 1 | G | J_TERMINAL_GND1 |  |  |  |  |  |  |
|  |  |  |  | 111 | 111 | 34044PQ00-G78-G |  | CONN,I/O,Terminal Blocks,R/A,Red,4mm,G,DIP-4 | FCI | VP02652700J0G | 1 | G | J_TERMINAL_48V1 |  |  |  |  |  |  |
|  |  |  |  | 112 | 112 | 3406ANQ00-317-G |  | CONN,Header,Power,V/T,Bla,10mm,30u,G,DIP-8 | MOLEX | 42819-4213 | 1 | G | J1 |  |  |  |  |  |  |
|  |  |  |  | 113 | 113 | 3406ALY00-317-G |  | CONN,Header,Shrouded,2X6,V/T,Bla,2mm,30u,G,SMD-12 | MOLEX | 87832-5523 | 1 | G | J2 |  |  |  |  |  |  |
|  |  |  |  | 114 | 114 | 3406ALW00-317-G |  | CONN,Header,Shrouded,2X5,V/T,Bla,2mm,30u,G,SMD-10 | MOLEX | 87832-5423 | 1 | G | J3 |  |  |  |  |  |  |
|  |  |  |  | 115 | 115 | 3406ARH00-309-G | - | CONN,Header,Socket,V/T,Bla,2.54mm,10u,G,DIP-8 | SAMTEC | ESQ-104-33-L-D | 1 | G | J10 |  |  |  |  |  |  |
|  |  |  |  | 116 | 116 | 320245F00-173-G |  | Linear IC,Power Controller,MAX6456UT29S+T,Others,NA,SOT-23,6P,G | MAXIM | MAX6456UT29S+T | 1 | G | PHAU2 |  |  |  |  |  |  |
